(kicad_pcb
	(version 20260206)
	(generator "pcbnew")
	(generator_version "10.0")
	(general
		(thickness 1.6)
		(legacy_teardrops no)
	)
	(paper "A4")
	(title_block
		(title "04192023_DAF0TMB3IC0_F0TG_MB_C_brd_V02_OCP.brd")
		(comment 1 "Grand Teton / footprints 5573-5578 of 8354")
	)
	(layers
		(0 "F.Cu" signal "TOP")
		(4 "In1.Cu" signal "GND")
		(6 "In2.Cu" signal "IN1")
		(8 "In3.Cu" signal "GND1")
		(10 "In4.Cu" signal "IN2")
		(12 "In5.Cu" signal "GND2")
		(14 "In6.Cu" signal "IN3")
		(16 "In7.Cu" signal "GND3")
		(18 "In8.Cu" signal "VCC")
		(20 "In9.Cu" signal "VCC1")
		(22 "In10.Cu" signal "GND4")
		(24 "In11.Cu" signal "IN4")
		(26 "In12.Cu" signal "GND5")
		(28 "In13.Cu" signal "IN5")
		(30 "In14.Cu" signal "GND6")
		(32 "In15.Cu" signal "IN6")
		(34 "In16.Cu" signal "GND7")
		(2 "B.Cu" signal "BOTTOM")
		(9 "F.Adhes" user "F.Adhesive")
		(11 "B.Adhes" user "B.Adhesive")
		(13 "F.Paste" user "Package Geometry/Pastemask Top")
		(15 "B.Paste" user "Package Geometry/Pastemask Bottom")
		(5 "F.SilkS" user "Ref Des/Silkscreen Top")
		(7 "B.SilkS" user "Ref Des/Silkscreen Bottom")
		(1 "F.Mask" user "Board Geometry/Soldermask Top")
		(3 "B.Mask" user "Board Geometry/Soldermask Bottom")
		(17 "Dwgs.User" user "User.Drawings")
		(19 "Cmts.User" user "User.Comments")
		(21 "Eco1.User" user "User.Eco1")
		(23 "Eco2.User" user "User.Eco2")
		(25 "Edge.Cuts" user "Board Geometry/Outline")
		(27 "Margin" user)
		(31 "F.CrtYd" user "Package Geometry/Place Bound Top")
		(29 "B.CrtYd" user "Package Geometry/Place Bound Bottom")
		(35 "F.Fab" user "Ref Des/Assembly Top")
		(33 "B.Fab" user "Ref Des/Assembly Bottom")
	)
	(footprint ""
		(layer "B.Cu")
		(at 104.716834 -249.368564 180)
		(property "Reference" "C2300"
			(at 0 0 0)
			(layer "B.SilkS")
			(hide yes)
			(effects
				(font
					(size 1.27 1.27)
				)
				(justify mirror)
			)
		)
		(property "Value" ""
			(at 0 0 0)
			(layer "B.Fab")
			(effects
				(font
					(size 1.27 1.27)
				)
				(justify mirror)
			)
		)
		(duplicate_pad_numbers_are_jumpers no)
		(fp_line
			(start 0.7874 0.4064)
			(end 0.7874 -0.4064)
			(stroke
				(width 0.1524)
				(type default)
			)
			(layer "B.SilkS")
		)
		(fp_line
			(start 0.7874 -0.4064)
			(end -0.7874 -0.4064)
			(stroke
				(width 0.1524)
				(type default)
			)
			(layer "B.SilkS")
		)
		(fp_line
			(start -0.7874 0.4064)
			(end 0.7874 0.4064)
			(stroke
				(width 0.1524)
				(type default)
			)
			(layer "B.SilkS")
		)
		(fp_line
			(start -0.7874 -0.4064)
			(end -0.7874 0.4064)
			(stroke
				(width 0.1524)
				(type default)
			)
			(layer "B.SilkS")
		)
		(fp_line
			(start 0.67945 0.3048)
			(end 0.67945 -0.305054)
			(stroke
				(width 0.1)
				(type default)
			)
			(layer "B.Fab")
		)
		(fp_line
			(start 0.67945 -0.305054)
			(end 0.12065 -0.305054)
			(stroke
				(width 0.1)
				(type default)
			)
			(layer "B.Fab")
		)
		(fp_line
			(start 0.12065 0.3048)
			(end 0.67945 0.3048)
			(stroke
				(width 0.1)
				(type default)
			)
			(layer "B.Fab")
		)
		(fp_line
			(start 0.12065 0.2794)
			(end 0.12065 0.3048)
			(stroke
				(width 0.1)
				(type default)
			)
			(layer "B.Fab")
		)
		(fp_line
			(start 0.12065 -0.2794)
			(end -0.12065 -0.2794)
			(stroke
				(width 0.1)
				(type default)
			)
			(layer "B.Fab")
		)
		(fp_line
			(start 0.12065 -0.305054)
			(end 0.12065 -0.2794)
			(stroke
				(width 0.1)
				(type default)
			)
			(layer "B.Fab")
		)
		(fp_line
			(start -0.120396 0.3048)
			(end -0.120396 0.2794)
			(stroke
				(width 0.1)
				(type default)
			)
			(layer "B.Fab")
		)
		(fp_line
			(start -0.120396 0.2794)
			(end 0.12065 0.2794)
			(stroke
				(width 0.1)
				(type default)
			)
			(layer "B.Fab")
		)
		(fp_line
			(start -0.12065 -0.2794)
			(end -0.12065 -0.3048)
			(stroke
				(width 0.1)
				(type default)
			)
			(layer "B.Fab")
		)
		(fp_line
			(start -0.12065 -0.3048)
			(end -0.67945 -0.3048)
			(stroke
				(width 0.1)
				(type default)
			)
			(layer "B.Fab")
		)
		(fp_line
			(start -0.67945 0.3048)
			(end -0.120396 0.3048)
			(stroke
				(width 0.1)
				(type default)
			)
			(layer "B.Fab")
		)
		(fp_line
			(start -0.67945 -0.3048)
			(end -0.67945 0.3048)
			(stroke
				(width 0.1)
				(type default)
			)
			(layer "B.Fab")
		)
		(pad "1" smd circle
			(at 0.40005 0)
			(size 0 0)
			(layers "B.Cu" "B.Mask" "B.Paste")
			(net "PVDDCR_CPU0_P1")
		)
		(pad "2" smd circle
			(at -0.40005 0)
			(size 0 0)
			(layers "B.Cu" "B.Mask" "B.Paste")
			(net "GND")
		)
	)
	(footprint ""
		(layer "B.Cu")
		(at 172.593 -98.135948 90)
		(property "Reference" "R6023"
			(at 0 0 90)
			(layer "B.SilkS")
			(hide yes)
			(effects
				(font
					(size 1.27 1.27)
				)
				(justify mirror)
			)
		)
		(property "Value" ""
			(at 0 0 90)
			(layer "B.Fab")
			(effects
				(font
					(size 1.27 1.27)
				)
				(justify mirror)
			)
		)
		(duplicate_pad_numbers_are_jumpers no)
		(fp_line
			(start 0.7874 -0.4064)
			(end -0.7874 -0.4064)
			(stroke
				(width 0.1524)
				(type default)
			)
			(layer "B.SilkS")
		)
		(fp_line
			(start -0.7874 -0.4064)
			(end -0.7874 0.4064)
			(stroke
				(width 0.1524)
				(type default)
			)
			(layer "B.SilkS")
		)
		(fp_line
			(start 0.7874 0.4064)
			(end 0.7874 -0.4064)
			(stroke
				(width 0.1524)
				(type default)
			)
			(layer "B.SilkS")
		)
		(fp_line
			(start -0.7874 0.4064)
			(end 0.7874 0.4064)
			(stroke
				(width 0.1524)
				(type default)
			)
			(layer "B.SilkS")
		)
		(fp_line
			(start 0.67945 -0.305054)
			(end 0.12065 -0.305054)
			(stroke
				(width 0.1)
				(type default)
			)
			(layer "B.Fab")
		)
		(fp_line
			(start 0.12065 -0.305054)
			(end 0.12065 -0.2794)
			(stroke
				(width 0.1)
				(type default)
			)
			(layer "B.Fab")
		)
		(fp_line
			(start -0.12065 -0.3048)
			(end -0.67945 -0.3048)
			(stroke
				(width 0.1)
				(type default)
			)
			(layer "B.Fab")
		)
		(fp_line
			(start -0.67945 -0.3048)
			(end -0.67945 0.3048)
			(stroke
				(width 0.1)
				(type default)
			)
			(layer "B.Fab")
		)
		(fp_line
			(start 0.12065 -0.2794)
			(end -0.12065 -0.2794)
			(stroke
				(width 0.1)
				(type default)
			)
			(layer "B.Fab")
		)
		(fp_line
			(start -0.12065 -0.2794)
			(end -0.12065 -0.3048)
			(stroke
				(width 0.1)
				(type default)
			)
			(layer "B.Fab")
		)
		(fp_line
			(start 0.12065 0.2794)
			(end 0.12065 0.3048)
			(stroke
				(width 0.1)
				(type default)
			)
			(layer "B.Fab")
		)
		(fp_line
			(start -0.120396 0.2794)
			(end 0.12065 0.2794)
			(stroke
				(width 0.1)
				(type default)
			)
			(layer "B.Fab")
		)
		(fp_line
			(start 0.67945 0.3048)
			(end 0.67945 -0.305054)
			(stroke
				(width 0.1)
				(type default)
			)
			(layer "B.Fab")
		)
		(fp_line
			(start 0.12065 0.3048)
			(end 0.67945 0.3048)
			(stroke
				(width 0.1)
				(type default)
			)
			(layer "B.Fab")
		)
		(fp_line
			(start -0.120396 0.3048)
			(end -0.120396 0.2794)
			(stroke
				(width 0.1)
				(type default)
			)
			(layer "B.Fab")
		)
		(fp_line
			(start -0.67945 0.3048)
			(end -0.120396 0.3048)
			(stroke
				(width 0.1)
				(type default)
			)
			(layer "B.Fab")
		)
		(pad "1" smd circle
			(at 0.40005 0 270)
			(size 0 0)
			(layers "B.Cu" "B.Mask" "B.Paste")
			(net "P3V3_AUX")
		)
		(pad "2" smd circle
			(at -0.40005 0 270)
			(size 0 0)
			(layers "B.Cu" "B.Mask" "B.Paste")
			(net "SGPIO_SCM_LD_<1>")
		)
	)
	(footprint ""
		(layer "B.Cu")
		(at 334.795876 -66.708782 90)
		(property "Reference" "R3091"
			(at 0 0 90)
			(layer "B.SilkS")
			(hide yes)
			(effects
				(font
					(size 1.27 1.27)
				)
				(justify mirror)
			)
		)
		(property "Value" ""
			(at 0 0 90)
			(layer "B.Fab")
			(effects
				(font
					(size 1.27 1.27)
				)
				(justify mirror)
			)
		)
		(duplicate_pad_numbers_are_jumpers no)
		(fp_line
			(start 0.7874 -0.4064)
			(end -0.7874 -0.4064)
			(stroke
				(width 0.1524)
				(type default)
			)
			(layer "B.SilkS")
		)
		(fp_line
			(start -0.7874 -0.4064)
			(end -0.7874 0.4064)
			(stroke
				(width 0.1524)
				(type default)
			)
			(layer "B.SilkS")
		)
		(fp_line
			(start 0.7874 0.4064)
			(end 0.7874 -0.4064)
			(stroke
				(width 0.1524)
				(type default)
			)
			(layer "B.SilkS")
		)
		(fp_line
			(start -0.7874 0.4064)
			(end 0.7874 0.4064)
			(stroke
				(width 0.1524)
				(type default)
			)
			(layer "B.SilkS")
		)
		(fp_line
			(start 0.67945 -0.305054)
			(end 0.12065 -0.305054)
			(stroke
				(width 0.1)
				(type default)
			)
			(layer "B.Fab")
		)
		(fp_line
			(start 0.12065 -0.305054)
			(end 0.12065 -0.2794)
			(stroke
				(width 0.1)
				(type default)
			)
			(layer "B.Fab")
		)
		(fp_line
			(start -0.12065 -0.3048)
			(end -0.67945 -0.3048)
			(stroke
				(width 0.1)
				(type default)
			)
			(layer "B.Fab")
		)
		(fp_line
			(start -0.67945 -0.3048)
			(end -0.67945 0.3048)
			(stroke
				(width 0.1)
				(type default)
			)
			(layer "B.Fab")
		)
		(fp_line
			(start 0.12065 -0.2794)
			(end -0.12065 -0.2794)
			(stroke
				(width 0.1)
				(type default)
			)
			(layer "B.Fab")
		)
		(fp_line
			(start -0.12065 -0.2794)
			(end -0.12065 -0.3048)
			(stroke
				(width 0.1)
				(type default)
			)
			(layer "B.Fab")
		)
		(fp_line
			(start 0.12065 0.2794)
			(end 0.12065 0.3048)
			(stroke
				(width 0.1)
				(type default)
			)
			(layer "B.Fab")
		)
		(fp_line
			(start -0.120396 0.2794)
			(end 0.12065 0.2794)
			(stroke
				(width 0.1)
				(type default)
			)
			(layer "B.Fab")
		)
		(fp_line
			(start 0.67945 0.3048)
			(end 0.67945 -0.305054)
			(stroke
				(width 0.1)
				(type default)
			)
			(layer "B.Fab")
		)
		(fp_line
			(start 0.12065 0.3048)
			(end 0.67945 0.3048)
			(stroke
				(width 0.1)
				(type default)
			)
			(layer "B.Fab")
		)
		(fp_line
			(start -0.120396 0.3048)
			(end -0.120396 0.2794)
			(stroke
				(width 0.1)
				(type default)
			)
			(layer "B.Fab")
		)
		(fp_line
			(start -0.67945 0.3048)
			(end -0.120396 0.3048)
			(stroke
				(width 0.1)
				(type default)
			)
			(layer "B.Fab")
		)
		(pad "1" smd circle
			(at 0.40005 0 270)
			(size 0 0)
			(layers "B.Cu" "B.Mask" "B.Paste")
			(net "LED_PWRGD_PVDD18_S5_P0_R")
		)
		(pad "2" smd circle
			(at -0.40005 0 270)
			(size 0 0)
			(layers "B.Cu" "B.Mask" "B.Paste")
			(net "P3V3_AUX")
		)
	)
	(footprint ""
		(layer "B.Cu")
		(at 151.275034 -201.977752 -90)
		(property "Reference" "C232"
			(at 0 0 90)
			(layer "B.SilkS")
			(hide yes)
			(effects
				(font
					(size 1.27 1.27)
				)
				(justify mirror)
			)
		)
		(property "Value" ""
			(at 0 0 90)
			(layer "B.Fab")
			(effects
				(font
					(size 1.27 1.27)
				)
				(justify mirror)
			)
		)
		(duplicate_pad_numbers_are_jumpers no)
		(fp_line
			(start -0.7874 0.4064)
			(end 0.7874 0.4064)
			(stroke
				(width 0.1524)
				(type default)
			)
			(layer "B.SilkS")
		)
		(fp_line
			(start 0.7874 0.4064)
			(end 0.7874 -0.4064)
			(stroke
				(width 0.1524)
				(type default)
			)
			(layer "B.SilkS")
		)
		(fp_line
			(start -0.7874 -0.4064)
			(end -0.7874 0.4064)
			(stroke
				(width 0.1524)
				(type default)
			)
			(layer "B.SilkS")
		)
		(fp_line
			(start 0.7874 -0.4064)
			(end -0.7874 -0.4064)
			(stroke
				(width 0.1524)
				(type default)
			)
			(layer "B.SilkS")
		)
		(fp_line
			(start -0.67945 0.3048)
			(end -0.120396 0.3048)
			(stroke
				(width 0.1)
				(type default)
			)
			(layer "B.Fab")
		)
		(fp_line
			(start -0.120396 0.3048)
			(end -0.120396 0.2794)
			(stroke
				(width 0.1)
				(type default)
			)
			(layer "B.Fab")
		)
		(fp_line
			(start 0.12065 0.3048)
			(end 0.67945 0.3048)
			(stroke
				(width 0.1)
				(type default)
			)
			(layer "B.Fab")
		)
		(fp_line
			(start 0.67945 0.3048)
			(end 0.67945 -0.305054)
			(stroke
				(width 0.1)
				(type default)
			)
			(layer "B.Fab")
		)
		(fp_line
			(start -0.120396 0.2794)
			(end 0.12065 0.2794)
			(stroke
				(width 0.1)
				(type default)
			)
			(layer "B.Fab")
		)
		(fp_line
			(start 0.12065 0.2794)
			(end 0.12065 0.3048)
			(stroke
				(width 0.1)
				(type default)
			)
			(layer "B.Fab")
		)
		(fp_line
			(start -0.12065 -0.2794)
			(end -0.12065 -0.3048)
			(stroke
				(width 0.1)
				(type default)
			)
			(layer "B.Fab")
		)
		(fp_line
			(start 0.12065 -0.2794)
			(end -0.12065 -0.2794)
			(stroke
				(width 0.1)
				(type default)
			)
			(layer "B.Fab")
		)
		(fp_line
			(start -0.67945 -0.3048)
			(end -0.67945 0.3048)
			(stroke
				(width 0.1)
				(type default)
			)
			(layer "B.Fab")
		)
		(fp_line
			(start -0.12065 -0.3048)
			(end -0.67945 -0.3048)
			(stroke
				(width 0.1)
				(type default)
			)
			(layer "B.Fab")
		)
		(fp_line
			(start 0.12065 -0.305054)
			(end 0.12065 -0.2794)
			(stroke
				(width 0.1)
				(type default)
			)
			(layer "B.Fab")
		)
		(fp_line
			(start 0.67945 -0.305054)
			(end 0.12065 -0.305054)
			(stroke
				(width 0.1)
				(type default)
			)
			(layer "B.Fab")
		)
		(pad "1" smd circle
			(at 0.40005 0 90)
			(size 0 0)
			(layers "B.Cu" "B.Mask" "B.Paste")
			(net "JTAG_CPU1_TRST_N")
		)
		(pad "2" smd circle
			(at -0.40005 0 90)
			(size 0 0)
			(layers "B.Cu" "B.Mask" "B.Paste")
			(net "GND")
		)
	)
	(footprint ""
		(layer "B.Cu")
		(at 53.391308 -390.560052 90)
		(property "Reference" "C256"
			(at 0 0 90)
			(layer "B.SilkS")
			(hide yes)
			(effects
				(font
					(size 1.27 1.27)
				)
				(justify mirror)
			)
		)
		(property "Value" ""
			(at 0 0 90)
			(layer "B.Fab")
			(effects
				(font
					(size 1.27 1.27)
				)
				(justify mirror)
			)
		)
		(duplicate_pad_numbers_are_jumpers no)
		(fp_line
			(start 0.7874 -0.4064)
			(end -0.7874 -0.4064)
			(stroke
				(width 0.1524)
				(type default)
			)
			(layer "B.SilkS")
		)
		(fp_line
			(start -0.7874 -0.4064)
			(end -0.7874 0.4064)
			(stroke
				(width 0.1524)
				(type default)
			)
			(layer "B.SilkS")
		)
		(fp_line
			(start 0.7874 0.4064)
			(end 0.7874 -0.4064)
			(stroke
				(width 0.1524)
				(type default)
			)
			(layer "B.SilkS")
		)
		(fp_line
			(start -0.7874 0.4064)
			(end 0.7874 0.4064)
			(stroke
				(width 0.1524)
				(type default)
			)
			(layer "B.SilkS")
		)
		(fp_line
			(start 0.67945 -0.305054)
			(end 0.12065 -0.305054)
			(stroke
				(width 0.1)
				(type default)
			)
			(layer "B.Fab")
		)
		(fp_line
			(start 0.12065 -0.305054)
			(end 0.12065 -0.2794)
			(stroke
				(width 0.1)
				(type default)
			)
			(layer "B.Fab")
		)
		(fp_line
			(start -0.12065 -0.3048)
			(end -0.67945 -0.3048)
			(stroke
				(width 0.1)
				(type default)
			)
			(layer "B.Fab")
		)
		(fp_line
			(start -0.67945 -0.3048)
			(end -0.67945 0.3048)
			(stroke
				(width 0.1)
				(type default)
			)
			(layer "B.Fab")
		)
		(fp_line
			(start 0.12065 -0.2794)
			(end -0.12065 -0.2794)
			(stroke
				(width 0.1)
				(type default)
			)
			(layer "B.Fab")
		)
		(fp_line
			(start -0.12065 -0.2794)
			(end -0.12065 -0.3048)
			(stroke
				(width 0.1)
				(type default)
			)
			(layer "B.Fab")
		)
		(fp_line
			(start 0.12065 0.2794)
			(end 0.12065 0.3048)
			(stroke
				(width 0.1)
				(type default)
			)
			(layer "B.Fab")
		)
		(fp_line
			(start -0.120396 0.2794)
			(end 0.12065 0.2794)
			(stroke
				(width 0.1)
				(type default)
			)
			(layer "B.Fab")
		)
		(fp_line
			(start 0.67945 0.3048)
			(end 0.67945 -0.305054)
			(stroke
				(width 0.1)
				(type default)
			)
			(layer "B.Fab")
		)
		(fp_line
			(start 0.12065 0.3048)
			(end 0.67945 0.3048)
			(stroke
				(width 0.1)
				(type default)
			)
			(layer "B.Fab")
		)
		(fp_line
			(start -0.120396 0.3048)
			(end -0.120396 0.2794)
			(stroke
				(width 0.1)
				(type default)
			)
			(layer "B.Fab")
		)
		(fp_line
			(start -0.67945 0.3048)
			(end -0.120396 0.3048)
			(stroke
				(width 0.1)
				(type default)
			)
			(layer "B.Fab")
		)
		(pad "1" smd circle
			(at 0.40005 0 270)
			(size 0 0)
			(layers "B.Cu" "B.Mask" "B.Paste")
			(net "P0V9_CPU1_RT_2D")
		)
		(pad "2" smd circle
			(at -0.40005 0 270)
			(size 0 0)
			(layers "B.Cu" "B.Mask" "B.Paste")
			(net "GND")
		)
	)
	(footprint ""
		(layer "B.Cu")
		(at 22.479 -363.347 180)
		(property "Reference" "R240"
			(at 0 0 0)
			(layer "B.SilkS")
			(hide yes)
			(effects
				(font
					(size 1.27 1.27)
				)
				(justify mirror)
			)
		)
		(property "Value" ""
			(at 0 0 0)
			(layer "B.Fab")
			(effects
				(font
					(size 1.27 1.27)
				)
				(justify mirror)
			)
		)
		(duplicate_pad_numbers_are_jumpers no)
		(fp_line
			(start 0.7874 0.4064)
			(end 0.7874 -0.4064)
			(stroke
				(width 0.1524)
				(type default)
			)
			(layer "B.SilkS")
		)
		(fp_line
			(start 0.7874 -0.4064)
			(end -0.7874 -0.4064)
			(stroke
				(width 0.1524)
				(type default)
			)
			(layer "B.SilkS")
		)
		(fp_line
			(start -0.7874 0.4064)
			(end 0.7874 0.4064)
			(stroke
				(width 0.1524)
				(type default)
			)
			(layer "B.SilkS")
		)
		(fp_line
			(start -0.7874 -0.4064)
			(end -0.7874 0.4064)
			(stroke
				(width 0.1524)
				(type default)
			)
			(layer "B.SilkS")
		)
		(fp_line
			(start 0.67945 0.3048)
			(end 0.67945 -0.305054)
			(stroke
				(width 0.1)
				(type default)
			)
			(layer "B.Fab")
		)
		(fp_line
			(start 0.67945 -0.305054)
			(end 0.12065 -0.305054)
			(stroke
				(width 0.1)
				(type default)
			)
			(layer "B.Fab")
		)
		(fp_line
			(start 0.12065 0.3048)
			(end 0.67945 0.3048)
			(stroke
				(width 0.1)
				(type default)
			)
			(layer "B.Fab")
		)
		(fp_line
			(start 0.12065 0.2794)
			(end 0.12065 0.3048)
			(stroke
				(width 0.1)
				(type default)
			)
			(layer "B.Fab")
		)
		(fp_line
			(start 0.12065 -0.2794)
			(end -0.12065 -0.2794)
			(stroke
				(width 0.1)
				(type default)
			)
			(layer "B.Fab")
		)
		(fp_line
			(start 0.12065 -0.305054)
			(end 0.12065 -0.2794)
			(stroke
				(width 0.1)
				(type default)
			)
			(layer "B.Fab")
		)
		(fp_line
			(start -0.120396 0.3048)
			(end -0.120396 0.2794)
			(stroke
				(width 0.1)
				(type default)
			)
			(layer "B.Fab")
		)
		(fp_line
			(start -0.120396 0.2794)
			(end 0.12065 0.2794)
			(stroke
				(width 0.1)
				(type default)
			)
			(layer "B.Fab")
		)
		(fp_line
			(start -0.12065 -0.2794)
			(end -0.12065 -0.3048)
			(stroke
				(width 0.1)
				(type default)
			)
			(layer "B.Fab")
		)
		(fp_line
			(start -0.12065 -0.3048)
			(end -0.67945 -0.3048)
			(stroke
				(width 0.1)
				(type default)
			)
			(layer "B.Fab")
		)
		(fp_line
			(start -0.67945 0.3048)
			(end -0.120396 0.3048)
			(stroke
				(width 0.1)
				(type default)
			)
			(layer "B.Fab")
		)
		(fp_line
			(start -0.67945 -0.3048)
			(end -0.67945 0.3048)
			(stroke
				(width 0.1)
				(type default)
			)
			(layer "B.Fab")
		)
		(pad "1" smd circle
			(at 0.40005 0)
			(size 0 0)
			(layers "B.Cu" "B.Mask" "B.Paste")
			(net "PVDDCR_CPU1_P1_RESET_N")
		)
		(pad "2" smd circle
			(at -0.40005 0)
			(size 0 0)
			(layers "B.Cu" "B.Mask" "B.Paste")
			(net "PVDDCR_CPU1_P1_RESET_N_R")
		)
	)
)
